(kicad_pcb
	(version 20240108)
	(generator "pcbnew")
	(generator_version "8.0")
	(general
		(thickness 1.62)
		(legacy_teardrops no)
	)
	(paper "A4")
	(title_block
		(title "Jetson Orin Baseboard")
		(date "2025-03-12")
		(rev "1.3.4")
		(company "Antmicro Ltd")
		(comment 1 "www.antmicro.com")
		(comment 9 "footprints 247-248 of 677")
	)
	(layers
		(0 "F.Cu" signal)
		(1 "In1.Cu" signal)
		(2 "In2.Cu" signal)
		(3 "In3.Cu" signal)
		(4 "In4.Cu" jumper)
		(5 "In5.Cu" signal)
		(6 "In6.Cu" signal)
		(31 "B.Cu" signal)
		(32 "B.Adhes" user "B.Adhesive")
		(33 "F.Adhes" user "F.Adhesive")
		(34 "B.Paste" user)
		(35 "F.Paste" user)
		(36 "B.SilkS" user "B.Silkscreen")
		(37 "F.SilkS" user "F.Silkscreen")
		(38 "B.Mask" user)
		(39 "F.Mask" user)
		(40 "Dwgs.User" user "User.Drawings")
		(41 "Cmts.User" user "User.Comments")
		(42 "Eco1.User" user "User.Eco1")
		(43 "Eco2.User" user "User.Eco2")
		(44 "Edge.Cuts" user)
		(45 "Margin" user)
		(46 "B.CrtYd" user "B.Courtyard")
		(47 "F.CrtYd" user "F.Courtyard")
		(48 "B.Fab" user)
		(49 "F.Fab" user)
	)
	(footprint "antmicro-footprints:USB-C_Receptacle_WE_632723300011"
		(layer "F.Cu")
		(at 74.75 123.75)
		(property "Reference" "J4"
			(at 3.06 -5.33 0)
			(layer "F.SilkS")
			(effects
				(font
					(size 0.7 0.7)
					(thickness 0.15)
				)
				(justify left bottom)
			)
		)
		(property "Value" "USB-C_WE_632723300011"
			(at 6.03 6.14 90)
			(layer "F.Fab")
			(effects
				(font
					(size 0.7 0.7)
					(thickness 0.15)
				)
				(justify left bottom)
			)
		)
		(property "Footprint" "antmicro-footprints:USB-C_Receptacle_WE_632723300011"
			(at 0 0 0)
			(layer "F.Fab")
			(hide yes)
			(effects
				(font
					(size 1.27 1.27)
					(thickness 0.15)
				)
			)
		)
		(property "Datasheet" "https://www.we-online.com/components/products/datasheet/632723300011.pdf"
			(at 0 0 0)
			(layer "F.Fab")
			(hide yes)
			(effects
				(font
					(size 1.27 1.27)
					(thickness 0.15)
				)
			)
		)
		(property "Author" "Antmicro"
			(at 0 0 0)
			(layer "F.Fab")
			(hide yes)
			(effects
				(font
					(size 1 1)
					(thickness 0.15)
				)
			)
		)
		(property "License" "Apache-2.0"
			(at 0 0 0)
			(layer "F.Fab")
			(hide yes)
			(effects
				(font
					(size 1 1)
					(thickness 0.15)
				)
			)
		)
		(property "MPN" "632723300011"
			(at 0 0 0)
			(layer "F.Fab")
			(hide yes)
			(effects
				(font
					(size 1 1)
					(thickness 0.15)
				)
			)
		)
		(property "Manufacturer" "Würth Elektronik"
			(at 0 0 0)
			(layer "F.Fab")
			(hide yes)
			(effects
				(font
					(size 1 1)
					(thickness 0.15)
				)
			)
		)
		(sheetname "USB Debug, DP")
		(sheetfile "usb.kicad_sch")
		(attr smd)
		(fp_line
			(start -4.4 -4.899)
			(end -4.4 -4.2)
			(stroke
				(width 0.15)
				(type solid)
			)
			(layer "F.SilkS")
		)
		(fp_line
			(start -4.4 -4.899)
			(end -2.999 -4.899)
			(stroke
				(width 0.15)
				(type solid)
			)
			(layer "F.SilkS")
		)
		(fp_line
			(start -4.4 -2.2)
			(end -4.4 0.6)
			(stroke
				(width 0.15)
				(type solid)
			)
			(layer "F.SilkS")
		)
		(fp_line
			(start -4.4 2.4)
			(end -4.4 3.201)
			(stroke
				(width 0.15)
				(type solid)
			)
			(layer "F.SilkS")
		)
		(fp_line
			(start 3 -4.899)
			(end 4.401 -4.899)
			(stroke
				(width 0.15)
				(type solid)
			)
			(layer "F.SilkS")
		)
		(fp_line
			(start 4.401 -4.2)
			(end 4.401 -4.899)
			(stroke
				(width 0.15)
				(type solid)
			)
			(layer "F.SilkS")
		)
		(fp_line
			(start 4.401 -2.2)
			(end 4.401 0.6)
			(stroke
				(width 0.15)
				(type solid)
			)
			(layer "F.SilkS")
		)
		(fp_line
			(start 4.401 2.4)
			(end 4.401 3.201)
			(stroke
				(width 0.15)
				(type solid)
			)
			(layer "F.SilkS")
		)
		(fp_circle
			(center -3.299 -5.598)
			(end -3.249 -5.598)
			(stroke
				(width 0.15)
				(type solid)
			)
			(fill solid)
			(layer "F.SilkS")
		)
		(fp_line
			(start -4.9 -5.4)
			(end -3.4 -5.4)
			(stroke
				(width 0.05)
				(type solid)
			)
			(layer "F.CrtYd")
		)
		(fp_line
			(start -4.9 6.5)
			(end -4.9 -5.4)
			(stroke
				(width 0.05)
				(type solid)
			)
			(layer "F.CrtYd")
		)
		(fp_line
			(start -3.4 -6.6)
			(end 3.4 -6.6)
			(stroke
				(width 0.05)
				(type solid)
			)
			(layer "F.CrtYd")
		)
		(fp_line
			(start -3.4 -5.4)
			(end -3.4 -6.6)
			(stroke
				(width 0.05)
				(type solid)
			)
			(layer "F.CrtYd")
		)
		(fp_line
			(start 3.4 -6.6)
			(end 3.4 -5.4)
			(stroke
				(width 0.05)
				(type solid)
			)
			(layer "F.CrtYd")
		)
		(fp_line
			(start 3.4 -5.4)
			(end 4.9 -5.4)
			(stroke
				(width 0.05)
				(type solid)
			)
			(layer "F.CrtYd")
		)
		(fp_line
			(start 4.9 -5.4)
			(end 4.9 6.5)
			(stroke
				(width 0.05)
				(type solid)
			)
			(layer "F.CrtYd")
		)
		(fp_line
			(start 4.9 6.5)
			(end -4.9 6.5)
			(stroke
				(width 0.05)
				(type solid)
			)
			(layer "F.CrtYd")
		)
		(fp_line
			(start -4.499 -5)
			(end -4.499 6.001)
			(stroke
				(width 0.15)
				(type solid)
			)
			(layer "F.Fab")
		)
		(fp_line
			(start -4.499 6.001)
			(end 4.499 6.001)
			(stroke
				(width 0.15)
				(type solid)
			)
			(layer "F.Fab")
		)
		(fp_line
			(start -2.999 -6.3)
			(end -2.999 -5)
			(stroke
				(width 0.15)
				(type solid)
			)
			(layer "F.Fab")
		)
		(fp_line
			(start -2.999 -5)
			(end -4.499 -5)
			(stroke
				(width 0.15)
				(type solid)
			)
			(layer "F.Fab")
		)
		(fp_line
			(start -2.979 -6.158)
			(end -2.859 -6.278)
			(stroke
				(width 0.15)
				(type solid)
			)
			(layer "F.Fab")
		)
		(fp_line
			(start 3 -6.3)
			(end -2.999 -6.3)
			(stroke
				(width 0.15)
				(type solid)
			)
			(layer "F.Fab")
		)
		(fp_line
			(start 3 -5)
			(end 3 -6.3)
			(stroke
				(width 0.15)
				(type solid)
			)
			(layer "F.Fab")
		)
		(fp_line
			(start 4.499 -5)
			(end 3 -5)
			(stroke
				(width 0.15)
				(type solid)
			)
			(layer "F.Fab")
		)
		(fp_line
			(start 4.499 6.001)
			(end 4.499 -5)
			(stroke
				(width 0.15)
				(type solid)
			)
			(layer "F.Fab")
		)
		(fp_text user "Author: Antmicro"
			(at -5.272 10.895 0)
			(layer "F.Fab")
			(hide yes)
			(effects
				(font
					(size 0.7 0.7)
					(thickness 0.15)
				)
				(justify left bottom)
			)
		)
		(fp_text user "License: Apache-2.0"
			(at -5.272 8.495 0)
			(layer "F.Fab")
			(hide yes)
			(effects
				(font
					(size 0.7 0.7)
					(thickness 0.15)
				)
				(justify left bottom)
			)
		)
		(fp_text user "${REFERENCE}"
			(at -5.272 9.695 0)
			(layer "F.Fab")
			(hide yes)
			(effects
				(font
					(size 0.7 0.7)
					(thickness 0.15)
				)
				(justify left bottom)
			)
		)
		(pad "" smd roundrect
			(at 0 -1.055)
			(size 0.2 1)
			(layers "F.Cu" "F.Paste" "F.Mask")
			(roundrect_rratio 0.25)
		)
		(pad "" smd roundrect
			(at 0 2.045)
			(size 0.2 1)
			(layers "F.Cu" "F.Paste" "F.Mask")
			(roundrect_rratio 0.25)
		)
		(pad "A1" smd roundrect
			(at -2.75 -5.635)
			(size 0.3 1.2)
			(layers "F.Cu" "F.Paste" "F.Mask")
			(roundrect_rratio 0.25)
			(net 1 "GND")
			(pinfunction "GND")
			(pintype "power_in")
		)
		(pad "A2" smd roundrect
			(at -2.25 -5.635)
			(size 0.3 1.2)
			(layers "F.Cu" "F.Paste" "F.Mask")
			(roundrect_rratio 0.25)
			(net 258 "/USB Debug, DP/USBC0_CONN_TX1_P")
			(pinfunction "TX_{1}+")
			(pintype "bidirectional")
		)
		(pad "A3" smd roundrect
			(at -1.75 -5.635)
			(size 0.3 1.2)
			(layers "F.Cu" "F.Paste" "F.Mask")
			(roundrect_rratio 0.25)
			(net 198 "/USB Debug, DP/USBC0_CONN_TX1_N")
			(pinfunction "TX_{1}-")
			(pintype "bidirectional")
		)
		(pad "A4" smd roundrect
			(at -1.25 -5.635)
			(size 0.3 1.2)
			(layers "F.Cu" "F.Paste" "F.Mask")
			(roundrect_rratio 0.25)
			(net 261 "/USB Debug, DP/USBC0_VBUS")
			(pinfunction "VBUS")
			(pintype "passive")
		)
		(pad "A5" smd roundrect
			(at -0.75 -5.635)
			(size 0.3 1.2)
			(layers "F.Cu" "F.Paste" "F.Mask")
			(roundrect_rratio 0.25)
			(net 277 "/USB Debug, DP/USBC0_CC1")
			(pinfunction "CC_{1}")
			(pintype "bidirectional")
		)
		(pad "A6" smd roundrect
			(at -0.25 -5.635)
			(size 0.3 1.2)
			(layers "F.Cu" "F.Paste" "F.Mask")
			(roundrect_rratio 0.25)
			(net 439 "USB2_D_P")
			(pinfunction "D_{A}+")
			(pintype "bidirectional")
		)
		(pad "A7" smd roundrect
			(at 0.25 -5.635)
			(size 0.3 1.2)
			(layers "F.Cu" "F.Paste" "F.Mask")
			(roundrect_rratio 0.25)
			(net 437 "USB2_D_N")
			(pinfunction "D_{A}-")
			(pintype "bidirectional")
		)
		(pad "A8" smd roundrect
			(at 0.75 -5.635)
			(size 0.3 1.2)
			(layers "F.Cu" "F.Paste" "F.Mask")
			(roundrect_rratio 0.25)
			(net 615 "/USB Debug, DP/USBC0_SBU_N")
			(pinfunction "SBU_{1}")
			(pintype "bidirectional")
		)
		(pad "A9" smd roundrect
			(at 1.25 -5.635)
			(size 0.3 1.2)
			(layers "F.Cu" "F.Paste" "F.Mask")
			(roundrect_rratio 0.25)
			(net 261 "/USB Debug, DP/USBC0_VBUS")
			(pinfunction "VBUS")
			(pintype "passive")
		)
		(pad "A10" smd roundrect
			(at 1.75 -5.635)
			(size 0.3 1.2)
			(layers "F.Cu" "F.Paste" "F.Mask")
			(roundrect_rratio 0.25)
			(net 125 "/USB Debug, DP/USBC0_RX2_N")
			(pinfunction "RX_{2}-")
			(pintype "bidirectional")
		)
		(pad "A11" smd roundrect
			(at 2.25 -5.635)
			(size 0.3 1.2)
			(layers "F.Cu" "F.Paste" "F.Mask")
			(roundrect_rratio 0.25)
			(net 151 "/USB Debug, DP/USBC0_RX2_P")
			(pinfunction "RX_{2}+")
			(pintype "bidirectional")
		)
		(pad "A12" smd roundrect
			(at 2.75 -5.635)
			(size 0.3 1.2)
			(layers "F.Cu" "F.Paste" "F.Mask")
			(roundrect_rratio 0.25)
			(net 1 "GND")
			(pinfunction "GND")
			(pintype "passive")
		)
		(pad "B1" thru_hole circle
			(at 2.8 -4.385)
			(size 0.65 0.65)
			(drill 0.3)
			(layers "*.Cu" "*.Mask")
			(remove_unused_layers no)
			(net 1 "GND")
			(pinfunction "GND")
			(pintype "passive")
		)
		(pad "B2" thru_hole circle
			(at 2.4 -3.685)
			(size 0.65 0.65)
			(drill 0.3)
			(layers "*.Cu" "*.Mask")
			(remove_unused_layers no)
			(net 260 "/USB Debug, DP/USBC0_CONN_TX2_P")
			(pinfunction "TX_{2}+")
			(pintype "bidirectional")
		)
		(pad "B3" thru_hole circle
			(at 1.6 -3.685)
			(size 0.65 0.65)
			(drill 0.3)
			(layers "*.Cu" "*.Mask")
			(remove_unused_layers no)
			(net 201 "/USB Debug, DP/USBC0_CONN_TX2_N")
			(pinfunction "TX_{2}-")
			(pintype "bidirectional")
		)
		(pad "B4" thru_hole circle
			(at 1.2 -4.385)
			(size 0.65 0.65)
			(drill 0.3)
			(layers "*.Cu" "*.Mask")
			(remove_unused_layers no)
			(net 261 "/USB Debug, DP/USBC0_VBUS")
			(pinfunction "VBUS")
			(pintype "passive")
		)
		(pad "B5" thru_hole circle
			(at 0.8 -3.685)
			(size 0.65 0.65)
			(drill 0.3)
			(layers "*.Cu" "*.Mask")
			(remove_unused_layers no)
			(net 278 "/USB Debug, DP/USBC0_CC2")
			(pinfunction "CC_{2}")
			(pintype "bidirectional")
		)
		(pad "B6" thru_hole circle
			(at 0.4 -4.385)
			(size 0.65 0.65)
			(drill 0.3)
			(layers "*.Cu" "*.Mask")
			(remove_unused_layers no)
			(net 439 "USB2_D_P")
			(pinfunction "D_{B}+")
			(pintype "bidirectional")
		)
		(pad "B7" thru_hole circle
			(at -0.4 -4.385)
			(size 0.65 0.65)
			(drill 0.3)
			(layers "*.Cu" "*.Mask")
			(remove_unused_layers no)
			(net 437 "USB2_D_N")
			(pinfunction "D_{B}-")
			(pintype "bidirectional")
		)
		(pad "B8" thru_hole circle
			(at -0.8 -3.685)
			(size 0.65 0.65)
			(drill 0.3)
			(layers "*.Cu" "*.Mask")
			(remove_unused_layers no)
			(net 614 "/USB Debug, DP/USBC0_SBU_P")
			(pinfunction "SBU_{2}")
			(pintype "bidirectional")
		)
		(pad "B9" thru_hole circle
			(at -1.2 -4.385)
			(size 0.65 0.65)
			(drill 0.3)
			(layers "*.Cu" "*.Mask")
			(remove_unused_layers no)
			(net 261 "/USB Debug, DP/USBC0_VBUS")
			(pinfunction "VBUS")
			(pintype "passive")
		)
		(pad "B10" thru_hole circle
			(at -1.6 -3.685)
			(size 0.65 0.65)
			(drill 0.3)
			(layers "*.Cu" "*.Mask")
			(remove_unused_layers no)
			(net 152 "/USB Debug, DP/USBC0_RX1_N")
			(pinfunction "RX_{1}-")
			(pintype "bidirectional")
		)
		(pad "B11" thru_hole circle
			(at -2.4 -3.685)
			(size 0.65 0.65)
			(drill 0.3)
			(layers "*.Cu" "*.Mask")
			(remove_unused_layers no)
			(net 154 "/USB Debug, DP/USBC0_RX1_P")
			(pinfunction "RX_{1}+")
			(pintype "bidirectional")
		)
		(pad "B12" thru_hole circle
			(at -2.8 -4.385)
			(size 0.65 0.65)
			(drill 0.3)
			(layers "*.Cu" "*.Mask")
			(remove_unused_layers no)
			(net 1 "GND")
			(pinfunction "GND")
			(pintype "passive")
		)
		(pad "SH" thru_hole oval
			(at -4.27 -3.235)
			(size 1 1.6)
			(drill oval 0.6 1.2)
			(layers "*.Cu" "*.Mask")
			(remove_unused_layers no)
			(net 1 "GND")
			(pinfunction "SH")
			(pintype "passive")
		)
		(pad "SH" thru_hole oval
			(at -4.27 1.495)
			(size 1 1.6)
			(drill oval 0.6 1.2)
			(layers "*.Cu" "*.Mask")
			(remove_unused_layers no)
			(net 1 "GND")
			(pinfunction "SH")
			(pintype "passive")
		)
		(pad "SH" thru_hole circle
			(at -2 -4.385)
			(size 0.65 0.65)
			(drill 0.3)
			(layers "*.Cu" "*.Mask")
			(remove_unused_layers no)
			(net 1 "GND")
			(pinfunction "SH")
			(pintype "passive")
		)
		(pad "SH" thru_hole circle
			(at 2 -4.385)
			(size 0.65 0.65)
			(drill 0.3)
			(layers "*.Cu" "*.Mask")
			(remove_unused_layers no)
			(net 1 "GND")
			(pinfunction "SH")
			(pintype "passive")
		)
		(pad "SH" thru_hole oval
			(at 4.27 -3.235)
			(size 1 1.6)
			(drill oval 0.6 1.2)
			(layers "*.Cu" "*.Mask")
			(remove_unused_layers no)
			(net 1 "GND")
			(pinfunction "SH")
			(pintype "passive")
		)
		(pad "SH" thru_hole oval
			(at 4.27 1.495)
			(size 1 1.6)
			(drill oval 0.6 1.2)
			(layers "*.Cu" "*.Mask")
			(remove_unused_layers no)
			(net 1 "GND")
			(pinfunction "SH")
			(pintype "passive")
		)
	)
	(footprint "antmicro-footprints:C_0402_1005Metric"
		(layer "F.Cu")
		(at 54.81 89.625 90)
		(descr "Capacitor SMD 0402")
		(tags "capacitor SMD 0402")
		(property "Reference" "C161"
			(at -1.135 -0.6 90)
			(layer "F.SilkS")
			(effects
				(font
					(size 0.7 0.7)
					(thickness 0.15)
				)
				(justify left bottom)
			)
		)
		(property "Value" "C_1n_16V_X7R_0402"
			(at -1.022927 2.155213 90)
			(layer "F.Fab")
			(effects
				(font
					(size 0.7 0.7)
					(thickness 0.15)
				)
				(justify left bottom)
			)
		)
		(property "Footprint" "antmicro-footprints:C_0402_1005Metric"
			(at 0 0 90)
			(layer "F.Fab")
			(hide yes)
			(effects
				(font
					(size 1.27 1.27)
					(thickness 0.15)
				)
			)
		)
		(property "Datasheet" "https://www.kemet.com/en/us/capacitors/product/C0402C102J4RACTU.html"
			(at 0 0 90)
			(layer "F.Fab")
			(hide yes)
			(effects
				(font
					(size 1.27 1.27)
					(thickness 0.15)
				)
			)
		)
		(property "Description" "SMD Multilayer Ceramic Capacitor, 1nF, 16V, 0402, ±5%, X7R"
			(at 0 0 90)
			(layer "F.Fab")
			(hide yes)
			(effects
				(font
					(size 1.27 1.27)
					(thickness 0.15)
				)
			)
		)
		(property "MPN" "C0402C102J4RACTU"
			(at 0 0 90)
			(unlocked yes)
			(layer "F.Fab")
			(hide yes)
			(effects
				(font
					(size 1 1)
					(thickness 0.15)
				)
			)
		)
		(property "Val" "1n"
			(at 0 0 90)
			(unlocked yes)
			(layer "F.Fab")
			(hide yes)
			(effects
				(font
					(size 1 1)
					(thickness 0.15)
				)
			)
		)
		(property "Voltage" "16V"
			(at 0 0 90)
			(unlocked yes)
			(layer "F.Fab")
			(hide yes)
			(effects
				(font
					(size 1 1)
					(thickness 0.15)
				)
			)
		)
		(property "Dielectric" "X7R"
			(at 0 0 90)
			(unlocked yes)
			(layer "F.Fab")
			(hide yes)
			(effects
				(font
					(size 1 1)
					(thickness 0.15)
				)
			)
		)
		(property "Manufacturer" "KEMET"
			(at 0 0 90)
			(unlocked yes)
			(layer "F.Fab")
			(hide yes)
			(effects
				(font
					(size 1 1)
					(thickness 0.15)
				)
			)
		)
		(property "License" "Apache-2.0"
			(at 0 0 90)
			(unlocked yes)
			(layer "F.Fab")
			(hide yes)
			(effects
				(font
					(size 1 1)
					(thickness 0.15)
				)
			)
		)
		(property "Author" "Antmicro"
			(at 0 0 90)
			(unlocked yes)
			(layer "F.Fab")
			(hide yes)
			(effects
				(font
					(size 1 1)
					(thickness 0.15)
				)
			)
		)
		(sheetname "Supply")
		(sheetfile "supply.kicad_sch")
		(attr smd)
		(fp_rect
			(start -0.925 -0.47)
			(end 0.925 0.47)
			(stroke
				(width 0.05)
				(type default)
			)
			(fill none)
			(layer "F.CrtYd")
		)
		(fp_line
			(start 0.504 -0.25)
			(end 0.504 0.248)
			(stroke
				(width 0.15)
				(type solid)
			)
			(layer "F.Fab")
		)
		(fp_line
			(start -0.494 -0.25)
			(end 0.504 -0.25)
			(stroke
				(width 0.15)
				(type solid)
			)
			(layer "F.Fab")
		)
		(fp_line
			(start 0.504 0.248)
			(end -0.494 0.248)
			(stroke
				(width 0.15)
				(type solid)
			)
			(layer "F.Fab")
		)
		(fp_line
			(start -0.494 0.248)
			(end -0.494 -0.25)
			(stroke
				(width 0.15)
				(type solid)
			)
			(layer "F.Fab")
		)
		(fp_text user "${REFERENCE}"
			(at -0.939 4.599 90)
			(layer "F.Fab")
			(hide yes)
			(effects
				(font
					(size 0.7 0.7)
					(thickness 0.15)
				)
				(justify left bottom)
			)
		)
		(fp_text user "Author: Antmicro"
			(at -0.939 3.399 90)
			(layer "F.Fab")
			(hide yes)
			(effects
				(font
					(size 0.7 0.7)
					(thickness 0.15)
				)
				(justify left bottom)
			)
		)
		(fp_text user "License: Apache-2.0"
			(at -0.939 5.799 90)
			(layer "F.Fab")
			(hide yes)
			(effects
				(font
					(size 0.7 0.7)
					(thickness 0.15)
				)
				(justify left bottom)
			)
		)
		(pad "1" smd roundrect
			(at -0.48 0 90)
			(size 0.59 0.64)
			(layers "F.Cu" "F.Paste" "F.Mask")
			(roundrect_rratio 0.25)
			(net 1 "GND")
			(pintype "passive")
		)
		(pad "2" smd roundrect
			(at 0.48 0 90)
			(size 0.59 0.64)
			(layers "F.Cu" "F.Paste" "F.Mask")
			(roundrect_rratio 0.25)
			(net 751 "Net-(U29-DVDT)")
			(pintype "passive")
		)
	)
)
